(kicad_pcb
	(version 20260206)
	(generator "pcbnew")
	(generator_version "10.0")
	(general
		(thickness 1.6)
		(legacy_teardrops no)
	)
	(paper "A4")
	(title_block
		(title "v1-chassis-manager — T6M_CM_d_v01_1031_1645.brd")
		(comment 1 "Open CloudServer (Microsoft) / footprints 1283-1291 of 2512")
	)
	(layers
		(0 "F.Cu" signal "TOP")
		(4 "In1.Cu" signal "GND1")
		(6 "In2.Cu" signal "IN1")
		(8 "In3.Cu" signal "VCC1")
		(10 "In4.Cu" signal "VCC2")
		(12 "In5.Cu" signal "GND2")
		(14 "In6.Cu" signal "IN2")
		(16 "In7.Cu" signal "IN3")
		(18 "In8.Cu" signal "GND3")
		(2 "B.Cu" signal "BOTTOM")
		(9 "F.Adhes" user "F.Adhesive")
		(11 "B.Adhes" user "B.Adhesive")
		(13 "F.Paste" user "Package Geometry/Pastemask Top")
		(15 "B.Paste" user "Package Geometry/Pastemask Bottom")
		(5 "F.SilkS" user "Ref Des/Silkscreen Top")
		(7 "B.SilkS" user "Ref Des/Silkscreen Bottom")
		(1 "F.Mask" user "Board Geometry/Soldermask Top")
		(3 "B.Mask" user "Board Geometry/Soldermask Bottom")
		(17 "Dwgs.User" user "User.Drawings")
		(19 "Cmts.User" user "User.Comments")
		(21 "Eco1.User" user "User.Eco1")
		(23 "Eco2.User" user "User.Eco2")
		(25 "Edge.Cuts" user "Board Geometry/Outline")
		(27 "Margin" user)
		(31 "F.CrtYd" user "Package Geometry/Place Bound Top")
		(29 "B.CrtYd" user "Package Geometry/Place Bound Bottom")
		(35 "F.Fab" user "Ref Des/Assembly Top")
		(33 "B.Fab" user "Ref Des/Assembly Bottom")
	)
	(footprint ""
		(layer "F.Cu")
		(at 82.051144 -156.359352 90)
		(property "Reference" "PC9"
			(at -0.276098 0.648716 0)
			(unlocked yes)
			(layer "F.SilkS")
			(effects
				(font
					(size 0.7874 0.5842)
					(thickness 0.1524)
				)
				(justify left)
			)
		)
		(property "Value" ""
			(at 0 0 90)
			(layer "F.Fab")
			(effects
				(font
					(size 1.27 1.27)
				)
			)
		)
		(duplicate_pad_numbers_are_jumpers no)
		(fp_line
			(start 0.7874 -0.4064)
			(end 0.7874 0.4064)
			(stroke
				(width 0.1524)
				(type default)
			)
			(layer "F.SilkS")
		)
		(fp_line
			(start -0.7874 -0.4064)
			(end 0.7874 -0.4064)
			(stroke
				(width 0.1524)
				(type default)
			)
			(layer "F.SilkS")
		)
		(fp_line
			(start 0 0.381)
			(end 0 -0.381)
			(stroke
				(width 0.1524)
				(type default)
			)
			(layer "F.SilkS")
		)
		(fp_line
			(start 0.7874 0.4064)
			(end -0.7874 0.4064)
			(stroke
				(width 0.1524)
				(type default)
			)
			(layer "F.SilkS")
		)
		(fp_line
			(start -0.7874 0.4064)
			(end -0.7874 -0.4064)
			(stroke
				(width 0.1524)
				(type default)
			)
			(layer "F.SilkS")
		)
		(fp_poly
			(pts
				(xy -0.5334 0.254) (xy -0.635 0.254) (xy -0.635 0.2286) (xy -0.635 -0.254) (xy -0.5334 -0.254) (xy -0.5334 -0.2794)
				(xy 0.5334 -0.2794) (xy 0.5334 -0.254) (xy 0.635 -0.254) (xy 0.635 0.254) (xy 0.5334 0.254) (xy 0.5334 0.2794)
				(xy -0.508 0.2794) (xy -0.5334 0.2794)
			)
			(stroke
				(width 0)
				(type default)
			)
			(fill no)
			(layer "F.CrtYd")
		)
		(pad "1" smd rect
			(at 0.40005 0 90)
			(size 0.4572 0.508)
			(layers "F.Cu" "F.Mask" "F.Paste")
			(net "GND")
		)
		(pad "2" smd rect
			(at -0.40005 0 90)
			(size 0.4572 0.508)
			(layers "F.Cu" "F.Mask" "F.Paste")
			(net "P5V_STB_NODE1_SS")
		)
	)
	(footprint ""
		(layer "F.Cu")
		(at 179.622704 -11.53668 -90)
		(property "Reference" "R813"
			(at 0.8636 2.071624 90)
			(unlocked yes)
			(layer "F.SilkS")
			(effects
				(font
					(size 0.7874 0.5842)
					(thickness 0.1524)
				)
				(justify left)
			)
		)
		(property "Value" ""
			(at 0 0 270)
			(layer "F.Fab")
			(effects
				(font
					(size 1.27 1.27)
				)
			)
		)
		(duplicate_pad_numbers_are_jumpers no)
		(fp_line
			(start -0.7874 0.4064)
			(end -0.7874 -0.4064)
			(stroke
				(width 0.1524)
				(type default)
			)
			(layer "F.SilkS")
		)
		(fp_line
			(start 0.7874 0.4064)
			(end -0.7874 0.4064)
			(stroke
				(width 0.1524)
				(type default)
			)
			(layer "F.SilkS")
		)
		(fp_line
			(start -0.7874 -0.4064)
			(end 0.7874 -0.4064)
			(stroke
				(width 0.1524)
				(type default)
			)
			(layer "F.SilkS")
		)
		(fp_line
			(start 0.7874 -0.4064)
			(end 0.7874 0.4064)
			(stroke
				(width 0.1524)
				(type default)
			)
			(layer "F.SilkS")
		)
		(fp_poly
			(pts
				(xy -0.508 0.2794) (xy -0.508 0.2286) (xy -0.635 0.2286) (xy -0.635 -0.254) (xy -0.5334 -0.254)
				(xy -0.5334 -0.2794) (xy 0.5334 -0.2794) (xy 0.5334 -0.254) (xy 0.635 -0.254) (xy 0.635 0.254) (xy 0.5334 0.254)
				(xy 0.5334 0.2794)
			)
			(stroke
				(width 0)
				(type default)
			)
			(fill no)
			(layer "F.CrtYd")
		)
		(pad "1" smd rect
			(at 0.40005 0 270)
			(size 0.4572 0.508)
			(layers "F.Cu" "F.Mask" "F.Paste")
			(net "N53608970")
		)
		(pad "2" smd rect
			(at -0.40005 0 270)
			(size 0.4572 0.508)
			(layers "F.Cu" "F.Mask" "F.Paste")
			(net "GND")
		)
	)
	(footprint ""
		(layer "F.Cu")
		(at 125.07976 -185.205624 -90)
		(property "Reference" "C737"
			(at -4.725416 -0.073152 90)
			(unlocked yes)
			(layer "F.SilkS")
			(effects
				(font
					(size 0.7874 0.5842)
					(thickness 0.1524)
				)
				(justify left)
			)
		)
		(property "Value" ""
			(at 0 0 270)
			(layer "F.Fab")
			(effects
				(font
					(size 1.27 1.27)
				)
			)
		)
		(duplicate_pad_numbers_are_jumpers no)
		(fp_line
			(start -0.7874 0.4064)
			(end -0.7874 -0.4064)
			(stroke
				(width 0.1524)
				(type default)
			)
			(layer "F.SilkS")
		)
		(fp_line
			(start 0.7874 0.4064)
			(end -0.7874 0.4064)
			(stroke
				(width 0.1524)
				(type default)
			)
			(layer "F.SilkS")
		)
		(fp_line
			(start 0 0.381)
			(end 0 -0.381)
			(stroke
				(width 0.1524)
				(type default)
			)
			(layer "F.SilkS")
		)
		(fp_line
			(start -0.7874 -0.4064)
			(end 0.7874 -0.4064)
			(stroke
				(width 0.1524)
				(type default)
			)
			(layer "F.SilkS")
		)
		(fp_line
			(start 0.7874 -0.4064)
			(end 0.7874 0.4064)
			(stroke
				(width 0.1524)
				(type default)
			)
			(layer "F.SilkS")
		)
		(fp_poly
			(pts
				(xy -0.5334 0.254) (xy -0.635 0.254) (xy -0.635 0.2286) (xy -0.635 -0.254) (xy -0.5334 -0.254) (xy -0.5334 -0.2794)
				(xy 0.5334 -0.2794) (xy 0.5334 -0.254) (xy 0.635 -0.254) (xy 0.635 0.254) (xy 0.5334 0.254) (xy 0.5334 0.2794)
				(xy -0.508 0.2794) (xy -0.5334 0.2794)
			)
			(stroke
				(width 0)
				(type default)
			)
			(fill no)
			(layer "F.CrtYd")
		)
		(pad "1" smd rect
			(at 0.40005 0 270)
			(size 0.4572 0.508)
			(layers "F.Cu" "F.Mask" "F.Paste")
			(net "UART_T9_NODE4_RXD")
		)
		(pad "2" smd rect
			(at -0.40005 0 270)
			(size 0.4572 0.508)
			(layers "F.Cu" "F.Mask" "F.Paste")
			(net "GND")
		)
	)
	(footprint ""
		(layer "F.Cu")
		(at 36.280598 -76.35875)
		(property "Reference" "C112"
			(at -5.19938 -0.53594 0)
			(unlocked yes)
			(layer "F.SilkS")
			(effects
				(font
					(size 0.7874 0.5842)
					(thickness 0.1524)
				)
				(justify left)
			)
		)
		(property "Value" ""
			(at 0 0 0)
			(layer "F.Fab")
			(effects
				(font
					(size 1.27 1.27)
				)
			)
		)
		(duplicate_pad_numbers_are_jumpers no)
		(fp_line
			(start -0.7874 -0.4064)
			(end 0.7874 -0.4064)
			(stroke
				(width 0.1524)
				(type default)
			)
			(layer "F.SilkS")
		)
		(fp_line
			(start -0.7874 0.4064)
			(end -0.7874 -0.4064)
			(stroke
				(width 0.1524)
				(type default)
			)
			(layer "F.SilkS")
		)
		(fp_line
			(start 0 0.381)
			(end 0 -0.381)
			(stroke
				(width 0.1524)
				(type default)
			)
			(layer "F.SilkS")
		)
		(fp_line
			(start 0.7874 -0.4064)
			(end 0.7874 0.4064)
			(stroke
				(width 0.1524)
				(type default)
			)
			(layer "F.SilkS")
		)
		(fp_line
			(start 0.7874 0.4064)
			(end -0.7874 0.4064)
			(stroke
				(width 0.1524)
				(type default)
			)
			(layer "F.SilkS")
		)
		(fp_poly
			(pts
				(xy -0.5334 0.254) (xy -0.635 0.254) (xy -0.635 0.2286) (xy -0.635 -0.254) (xy -0.5334 -0.254) (xy -0.5334 -0.2794)
				(xy 0.5334 -0.2794) (xy 0.5334 -0.254) (xy 0.635 -0.254) (xy 0.635 0.254) (xy 0.5334 0.254) (xy 0.5334 0.2794)
				(xy -0.508 0.2794) (xy -0.5334 0.2794)
			)
			(stroke
				(width 0)
				(type default)
			)
			(fill no)
			(layer "F.CrtYd")
		)
		(pad "1" smd rect
			(at 0.40005 0)
			(size 0.4572 0.508)
			(layers "F.Cu" "F.Mask" "F.Paste")
			(net "P1V8_VCCASFRHPLL_NODE1")
		)
		(pad "2" smd rect
			(at -0.40005 0)
			(size 0.4572 0.508)
			(layers "F.Cu" "F.Mask" "F.Paste")
			(net "GND")
		)
	)
	(footprint ""
		(layer "F.Cu")
		(at 61.38418 -164.510212 -90)
		(property "Reference" "R1109"
			(at -1.53416 -0.204724 90)
			(unlocked yes)
			(layer "F.SilkS")
			(effects
				(font
					(size 0.7874 0.5842)
					(thickness 0.1524)
				)
				(justify left)
			)
		)
		(property "Value" ""
			(at 0 0 270)
			(layer "F.Fab")
			(effects
				(font
					(size 1.27 1.27)
				)
			)
		)
		(duplicate_pad_numbers_are_jumpers no)
		(fp_line
			(start -0.7874 0.4064)
			(end -0.7874 -0.4064)
			(stroke
				(width 0.1524)
				(type default)
			)
			(layer "F.SilkS")
		)
		(fp_line
			(start 0.7874 0.4064)
			(end -0.7874 0.4064)
			(stroke
				(width 0.1524)
				(type default)
			)
			(layer "F.SilkS")
		)
		(fp_line
			(start -0.7874 -0.4064)
			(end 0.7874 -0.4064)
			(stroke
				(width 0.1524)
				(type default)
			)
			(layer "F.SilkS")
		)
		(fp_line
			(start 0.7874 -0.4064)
			(end 0.7874 0.4064)
			(stroke
				(width 0.1524)
				(type default)
			)
			(layer "F.SilkS")
		)
		(fp_poly
			(pts
				(xy -0.508 0.2794) (xy -0.508 0.2286) (xy -0.635 0.2286) (xy -0.635 -0.254) (xy -0.5334 -0.254)
				(xy -0.5334 -0.2794) (xy 0.5334 -0.2794) (xy 0.5334 -0.254) (xy 0.635 -0.254) (xy 0.635 0.254) (xy 0.5334 0.254)
				(xy 0.5334 0.2794)
			)
			(stroke
				(width 0)
				(type default)
			)
			(fill no)
			(layer "F.CrtYd")
		)
		(pad "1" smd rect
			(at 0.40005 0 270)
			(size 0.4572 0.508)
			(layers "F.Cu" "F.Mask" "F.Paste")
			(net "FM_CPLD_NODE1_P5V_NODE1_EN_G")
		)
		(pad "2" smd rect
			(at -0.40005 0 270)
			(size 0.4572 0.508)
			(layers "F.Cu" "F.Mask" "F.Paste")
			(net "P3V3_STB_NODE1")
		)
	)
	(footprint ""
		(layer "F.Cu")
		(at 110.51032 -151.381968 -90)
		(property "Reference" "Q45"
			(at 4.080002 -0.417576 0)
			(unlocked yes)
			(layer "F.SilkS")
			(effects
				(font
					(size 0.7874 0.5842)
					(thickness 0.1524)
				)
			)
		)
		(property "Value" ""
			(at 0 0 270)
			(layer "F.Fab")
			(effects
				(font
					(size 1.27 1.27)
				)
			)
		)
		(duplicate_pad_numbers_are_jumpers no)
		(fp_line
			(start -1.488186 1.500124)
			(end -1.488186 -1.500124)
			(stroke
				(width 0.1524)
				(type default)
			)
			(layer "F.SilkS")
		)
		(fp_line
			(start 1.488186 1.500124)
			(end -1.488186 1.500124)
			(stroke
				(width 0.1524)
				(type default)
			)
			(layer "F.SilkS")
		)
		(fp_line
			(start -1.488186 -1.500124)
			(end 1.488186 -1.500124)
			(stroke
				(width 0.1524)
				(type default)
			)
			(layer "F.SilkS")
		)
		(fp_line
			(start 1.488186 -1.500124)
			(end 1.488186 1.500124)
			(stroke
				(width 0.1524)
				(type default)
			)
			(layer "F.SilkS")
		)
		(fp_poly
			(pts
				(xy -0.700024 1.500124) (xy 0.700024 1.500124) (xy 0.700024 0.3556) (xy 1.4224 0.3556) (xy 1.4224 -0.3556)
				(xy 0.700024 -0.3556) (xy 0.700024 -1.500124) (xy -0.700024 -1.500124) (xy -0.700024 -1.3208) (xy -1.4224 -1.3208)
				(xy -1.4224 -0.5842) (xy -0.700024 -0.5842) (xy -0.700024 0.5842) (xy -1.4224 0.5842) (xy -1.4224 1.3208)
				(xy -0.700024 1.3208)
			)
			(stroke
				(width 0)
				(type default)
			)
			(fill no)
			(layer "F.CrtYd")
		)
		(fp_line
			(start -0.700024 1.500124)
			(end -0.700024 -1.500124)
			(stroke
				(width 0.1)
				(type default)
			)
			(layer "F.Fab")
		)
		(fp_line
			(start 0.700024 1.500124)
			(end -0.700024 1.500124)
			(stroke
				(width 0.1)
				(type default)
			)
			(layer "F.Fab")
		)
		(fp_line
			(start -0.700024 -1.500124)
			(end 0.700024 -1.500124)
			(stroke
				(width 0.1)
				(type default)
			)
			(layer "F.Fab")
		)
		(fp_line
			(start 0.700024 -1.500124)
			(end 0.700024 1.500124)
			(stroke
				(width 0.1)
				(type default)
			)
			(layer "F.Fab")
		)
		(fp_text user "1"
			(at -0.439928 0.237744 0)
			(unlocked yes)
			(layer "F.SilkS")
			(effects
				(font
					(size 0.635 0.4064)
					(thickness 0.1524)
				)
			)
		)
		(fp_text user "3"
			(at -0.09779 -1.881378 0)
			(unlocked yes)
			(layer "F.SilkS")
			(effects
				(font
					(size 0.635 0.4064)
					(thickness 0.1524)
				)
			)
		)
		(fp_text user "2"
			(at 1.009396 -1.881378 0)
			(unlocked yes)
			(layer "F.SilkS")
			(effects
				(font
					(size 0.635 0.4064)
					(thickness 0.1524)
				)
			)
		)
		(fp_text user "2"
			(at -0.90805 1.8542 180)
			(unlocked yes)
			(layer "F.Fab")
			(effects
				(font
					(size 0.7874 0.5842)
					(thickness 0.000001)
				)
			)
		)
		(fp_text user "3"
			(at 2.15773 0 180)
			(unlocked yes)
			(layer "F.Fab")
			(effects
				(font
					(size 0.7874 0.5842)
					(thickness 0.000001)
				)
			)
		)
		(fp_text user "1"
			(at -0.90805 -1.8034 180)
			(unlocked yes)
			(layer "F.Fab")
			(effects
				(font
					(size 0.7874 0.5842)
					(thickness 0.000001)
				)
			)
		)
		(pad "1" smd rect
			(at -0.999998 -0.94996 180)
			(size 0.6096 0.7112)
			(layers "F.Cu" "F.Mask" "F.Paste")
			(net "N52411214")
		)
		(pad "2" smd rect
			(at -0.999998 0.94996 180)
			(size 0.6096 0.7112)
			(layers "F.Cu" "F.Mask" "F.Paste")
			(net "N52411159")
		)
		(pad "3" smd rect
			(at 0.999998 0 180)
			(size 0.6096 0.7112)
			(layers "F.Cu" "F.Mask" "F.Paste")
			(net "POWER_SW2_PWR_CTR_12V")
		)
	)
	(footprint ""
		(layer "F.Cu")
		(at 50.53076 -188.126624 90)
		(property "Reference" "R849"
			(at 4.548886 0.205232 90)
			(unlocked yes)
			(layer "F.SilkS")
			(effects
				(font
					(size 0.7874 0.5842)
					(thickness 0.1524)
				)
				(justify left)
			)
		)
		(property "Value" ""
			(at 0 0 90)
			(layer "F.Fab")
			(effects
				(font
					(size 1.27 1.27)
				)
			)
		)
		(duplicate_pad_numbers_are_jumpers no)
		(fp_line
			(start 0.7874 -0.4064)
			(end 0.7874 0.4064)
			(stroke
				(width 0.1524)
				(type default)
			)
			(layer "F.SilkS")
		)
		(fp_line
			(start -0.7874 -0.4064)
			(end 0.7874 -0.4064)
			(stroke
				(width 0.1524)
				(type default)
			)
			(layer "F.SilkS")
		)
		(fp_line
			(start 0.7874 0.4064)
			(end -0.7874 0.4064)
			(stroke
				(width 0.1524)
				(type default)
			)
			(layer "F.SilkS")
		)
		(fp_line
			(start -0.7874 0.4064)
			(end -0.7874 -0.4064)
			(stroke
				(width 0.1524)
				(type default)
			)
			(layer "F.SilkS")
		)
		(fp_poly
			(pts
				(xy -0.508 0.2794) (xy -0.508 0.2286) (xy -0.635 0.2286) (xy -0.635 -0.254) (xy -0.5334 -0.254)
				(xy -0.5334 -0.2794) (xy 0.5334 -0.2794) (xy 0.5334 -0.254) (xy 0.635 -0.254) (xy 0.635 0.254) (xy 0.5334 0.254)
				(xy 0.5334 0.2794)
			)
			(stroke
				(width 0)
				(type default)
			)
			(fill no)
			(layer "F.CrtYd")
		)
		(pad "1" smd rect
			(at 0.40005 0 90)
			(size 0.4572 0.508)
			(layers "F.Cu" "F.Mask" "F.Paste")
			(net "PSU3_AC_OK_R")
		)
		(pad "2" smd rect
			(at -0.40005 0 90)
			(size 0.4572 0.508)
			(layers "F.Cu" "F.Mask" "F.Paste")
			(net "GND")
		)
	)
	(footprint ""
		(layer "F.Cu")
		(at 8.553958 -9.179306 90)
		(property "Reference" "C180"
			(at -2.095246 -2.989834 90)
			(unlocked yes)
			(layer "F.SilkS")
			(effects
				(font
					(size 0.7874 0.5842)
					(thickness 0.1524)
				)
				(justify left)
			)
		)
		(property "Value" ""
			(at 0 0 90)
			(layer "F.Fab")
			(effects
				(font
					(size 1.27 1.27)
				)
			)
		)
		(duplicate_pad_numbers_are_jumpers no)
		(fp_line
			(start 0.7874 -0.4064)
			(end 0.7874 0.4064)
			(stroke
				(width 0.1524)
				(type default)
			)
			(layer "F.SilkS")
		)
		(fp_line
			(start -0.7874 -0.4064)
			(end 0.7874 -0.4064)
			(stroke
				(width 0.1524)
				(type default)
			)
			(layer "F.SilkS")
		)
		(fp_line
			(start 0 0.381)
			(end 0 -0.381)
			(stroke
				(width 0.1524)
				(type default)
			)
			(layer "F.SilkS")
		)
		(fp_line
			(start 0.7874 0.4064)
			(end -0.7874 0.4064)
			(stroke
				(width 0.1524)
				(type default)
			)
			(layer "F.SilkS")
		)
		(fp_line
			(start -0.7874 0.4064)
			(end -0.7874 -0.4064)
			(stroke
				(width 0.1524)
				(type default)
			)
			(layer "F.SilkS")
		)
		(fp_poly
			(pts
				(xy -0.5334 0.254) (xy -0.635 0.254) (xy -0.635 0.2286) (xy -0.635 -0.254) (xy -0.5334 -0.254) (xy -0.5334 -0.2794)
				(xy 0.5334 -0.2794) (xy 0.5334 -0.254) (xy 0.635 -0.254) (xy 0.635 0.254) (xy 0.5334 0.254) (xy 0.5334 0.2794)
				(xy -0.508 0.2794) (xy -0.5334 0.2794)
			)
			(stroke
				(width 0)
				(type default)
			)
			(fill no)
			(layer "F.CrtYd")
		)
		(pad "1" smd rect
			(at 0.40005 0 90)
			(size 0.4572 0.508)
			(layers "F.Cu" "F.Mask" "F.Paste")
			(net "P5V_STB_NODE1")
		)
		(pad "2" smd rect
			(at -0.40005 0 90)
			(size 0.4572 0.508)
			(layers "F.Cu" "F.Mask" "F.Paste")
			(net "GND")
		)
	)
	(footprint ""
		(layer "F.Cu")
		(at 13.965174 -16.260572 -90)
		(property "Reference" "C546"
			(at 1.500124 6.243574 90)
			(unlocked yes)
			(layer "F.SilkS")
			(effects
				(font
					(size 0.7874 0.5842)
					(thickness 0.1524)
				)
				(justify left)
			)
		)
		(property "Value" ""
			(at 0 0 270)
			(layer "F.Fab")
			(effects
				(font
					(size 1.27 1.27)
				)
			)
		)
		(duplicate_pad_numbers_are_jumpers no)
		(fp_line
			(start -0.7874 0.4064)
			(end -0.7874 -0.4064)
			(stroke
				(width 0.1524)
				(type default)
			)
			(layer "F.SilkS")
		)
		(fp_line
			(start 0.7874 0.4064)
			(end -0.7874 0.4064)
			(stroke
				(width 0.1524)
				(type default)
			)
			(layer "F.SilkS")
		)
		(fp_line
			(start 0 0.381)
			(end 0 -0.381)
			(stroke
				(width 0.1524)
				(type default)
			)
			(layer "F.SilkS")
		)
		(fp_line
			(start -0.7874 -0.4064)
			(end 0.7874 -0.4064)
			(stroke
				(width 0.1524)
				(type default)
			)
			(layer "F.SilkS")
		)
		(fp_line
			(start 0.7874 -0.4064)
			(end 0.7874 0.4064)
			(stroke
				(width 0.1524)
				(type default)
			)
			(layer "F.SilkS")
		)
		(fp_poly
			(pts
				(xy -0.5334 0.254) (xy -0.635 0.254) (xy -0.635 0.2286) (xy -0.635 -0.254) (xy -0.5334 -0.254) (xy -0.5334 -0.2794)
				(xy 0.5334 -0.2794) (xy 0.5334 -0.254) (xy 0.635 -0.254) (xy 0.635 0.254) (xy 0.5334 0.254) (xy 0.5334 0.2794)
				(xy -0.508 0.2794) (xy -0.5334 0.2794)
			)
			(stroke
				(width 0)
				(type default)
			)
			(fill no)
			(layer "F.CrtYd")
		)
		(pad "1" smd rect
			(at 0.40005 0 270)
			(size 0.4572 0.508)
			(layers "F.Cu" "F.Mask" "F.Paste")
			(net "N54251517")
		)
		(pad "2" smd rect
			(at -0.40005 0 270)
			(size 0.4572 0.508)
			(layers "F.Cu" "F.Mask" "F.Paste")
			(net "N54251519")
		)
	)
)
